FILE_TYPE = CONNECTIVITY;
{Allegro Design Entry HDL 17.4-2019 S026 (4007227) 1/17/2022}
"PAGE_NUMBER" = 182;
0"NC";
1"GND\g";
2"GND\g";
3"GND\g";
4"GND\g";
5"PVDD18_S5_P0\g";
6"GND\g";
7"PVDD11_S3_P0\g";
8"GND\g";
9"GND\g";
10"GND\g";
11"GND\g";
12"GND\g";
13"GND\g";
14"GND\g";
15"GND\g";
16"GND\g";
17"GND\g";
18"GND\g";
19"GND\g";
20"GND\g";
21"GND\g";
22"GND\g";
23"PVDD11_S3_P0_VMON";
24"VSENSE_VSS_SENSE_C_P0";
25"VSENSE_PVDD11_S3_P0_DP";
26"NC_PVDD11_S3_P0_PWM3";
27"P3V3_AUX\g";
28"P3V3_AUX\g";
29"P12V_AUX\g";
30"PVDD18_S5_P0\g";
31"GND\g";
32"GND\g";
33"GND\g";
34"P3V3_AUX\g";
35"GND\g";
36"GND\g";
37"P5V_AUX\g";
38"PVDD11_S3_P0_ADDR_CFG";
39"NC_PVDD11_S3_P0_IMON5";
40"NC_PVDD11_S3_P0_PWM5";
41"PVDD11_S3_P0_IMON1";
42"PVDD11_S3_P0_VCC";
43"PVDD11_S3_P0_PMSCL_R";
44"PVDD11_S3_P0_IMON2";
45"NC_PVDD11_S3_P0_SVTO";
46"PVDD11_S3_P0_RESET_N_R";
47"NC_PVDD11_S3_P0_IMON3";
48"NC_PVDD11_S3_P0_IMON4";
49"NC_PVDD11_S3_P0_PG1";
50"PVDD11_S3_P0_PMALERT_R";
51"PVDD11_S3_P0_EN_R";
52"PVDD11_S3_P0_PMSDA_R";
53"NC_PVDD11_S3_P0_PWM4";
54"VSENSE_PVDD11_S3_P0_R";
55"NC_PVDD11_S3_P0_PWM7";
56"PWRGD_PVDD11_S3_P0_R";
57"PVDD11_S3_P0_PWM2";
58"PVDD11_S3_P0_VCCS";
59"PVDD11_S3_P0_VINSEN";
60"PVDD11_S3_P0_TEMP0";
61"PVDD11_S3_P0_VDDIO";
62"NC_PVDD11_S3_P0_IMON7";
63"PVDD11_S3_P0_PWM1";
64"NC_PVDD11_S3_P0_PWM6";
65"NC_PVDD11_S3_P0_IMON6";
66"PVDD11_S3_P0_OCP_N_R";
67"PVDD11_S3_P0_TEMP1";
68"NC_PVDD11_S3_P0_PWM8";
69"NC_PVDD11_S3_P0_IMON8";
70"PWRGD_PVDD11_S3_P0";
71"PVDD11_S3_P0_PMALERT";
72"SMB_SCM_2_R6_SDA";
73"PVDD11_S3_P0_OCP_N";
74"SMB_SCM_2_R6_SCL";
75"PVDD11_S3_P0_EN";
76"PVDD11_S3_P0_RESET_N";
%"VCC_CORE"
"1","(-7650,950)","0","pure_quanta_power","I1";
;
HDL_POWER"P5V_AUX"
CDS_LIB"pure_quanta_power";
"A"37;
%"Q_RES"
"1","(-6275,2125)","0","pure_quanta","I13";
;
LOCATION"R8116"
$SEC"1"
CDS_SEC"1"
VALUE"0"
TOLERANCE"5%"
WATTAGE"1/16W"
PACK_TYPE"0402LF"
MATERIAL"EMPTY"
CDS_LIB"pure_quanta"
PART_NUMBER"CS00002JB13";
"B"
$PN"2"66;
"A"
$PN"1"73;
%"UNIVERSAL_GND"
"1","(-6900,3500)","0","pure_quanta_power","I14";
;
CDS_LIB"pure_quanta_power"
HDL_POWER"GND";
"A"1;
%"Q_RES"
"2","(-6900,3675)","0","pure_quanta","I15";
;
LOCATION"PR115"
$SEC"1"
CDS_SEC"1"
MATERIAL"CHIP"
WATTAGE"1/16W"
VALUE"49.9"
TOLERANCE"1%"
PACK_TYPE"0402LF"
CDS_LIB"pure_quanta"
PART_NUMBER"CS04992FB07";
"A"
$PN"1"24;
"B"
$PN"2"1;
%"Q_RES"
"1","(-6050,675)","0","pure_quanta","I16";
;
LOCATION"PR125"
$SEC"1"
CDS_SEC"1"
MATERIAL"CHIP"
PACK_TYPE"0402LF"
WATTAGE"1/16W"
TOLERANCE"5%"
VALUE"0"
CDS_LIB"pure_quanta"
PART_NUMBER"CS00002JB13";
"B"
$PN"2"59;
"A"
$PN"1"29;
%"UNIVERSAL_GND"
"1","(-5725,275)","0","pure_quanta_power","I17";
;
CDS_LIB"pure_quanta_power"
HDL_POWER"GND";
"A"2;
%"Q_RES"
"2","(-5725,475)","0","pure_quanta","I18";
;
LOCATION"PR601"
$SEC"1"
CDS_SEC"1"
WATTAGE"1/16W"
MATERIAL"EMPTY"
TOLERANCE"1%"
VALUE"4.99K"
PACK_TYPE"0402LF"
CDS_LIB"pure_quanta"
PART_NUMBER"CS24992FB07";
"A"
$PN"1"59;
"B"
$PN"2"2;
%"UNIVERSAL_GND"
"1","(-5400,275)","0","pure_quanta_power","I19";
;
CDS_LIB"pure_quanta_power"
HDL_POWER"GND";
"A"3;
%"Q_RES"
"1","(-7300,850)","0","pure_quanta","I2";
;
LOCATION"PR113"
$SEC"1"
CDS_SEC"1"
WATTAGE"1/16W"
TOLERANCE"1%"
PACK_TYPE"0402LF"
MATERIAL"CHIP"
VALUE"40.2K"
CDS_LIB"pure_quanta"
PART_NUMBER"CS34022FB04";
"B"
$PN"2"23;
"A"
$PN"1"37;
%"Q_CAP"
"1","(-5400,500)","0","pure_quanta","I20";
;
LOCATION"PC5"
SEC"1"
PACK_TYPE"0402"
VOLTAGE"25V"
VALUE"0.1UF"
TOLERANCE"10%"
MATERIAL"X7R"
CDS_LIB"pure_quanta"
SEC_TYPE"0402"
PART_NUMBER"CH4104K1B00";
"B"
$PN"2"3;
"A"
$PN"1"59;
%"UNIVERSAL_GND"
"1","(-5700,1075)","0","pure_quanta_power","I21";
;
CDS_LIB"pure_quanta_power"
HDL_POWER"GND";
"A"4;
%"Q_RES"
"2","(-5700,1275)","0","pure_quanta","I22";
;
LOCATION"PR126"
$SEC"1"
CDS_SEC"1"
PACK_TYPE"0402LF"
MATERIAL"CHIP"
TOLERANCE"1%"
VALUE"3.09K"
WATTAGE"1/16W"
CDS_LIB"pure_quanta"
PART_NUMBER"CS23092FB04";
"A"
$PN"1"38;
"B"
$PN"2"4;
%"UNIVERSAL_GND"
"1","(-5200,475)","0","pure_quanta_power","I23";
;
CDS_LIB"pure_quanta_power"
HDL_POWER"GND";
"A"36;
%"RAA229621GNPHA0"
"1","(-4425,3375)","0","pure_quanta","I24";
;
LOCATION"PU21"
$SEC"1"
CDS_SEC"1"
PART_TYPE"SMLF"
VALUE"RAA229621GNP#HA0"
MATERIAL"IC"
CDS_LIB"pure_quanta"
NEEDS_NO_SIZE"TRUE"
CDS_LMAN_SYM_OUTLINE"-550,2850,500,-2850"
PART_NUMBER"ARF0TGP4003";
"CS0"
$PN"30"69;
"PWM0"
$PN"1"68;
"TEMP1"
$PN"35"67;
"EN1||ADDR_CFG"
$PN"34"38;
"TH_GND"
$PN"TH"36;
"OCP_L \B"
$PN"33"66;
"CS2"
$PN"28"65;
"PWM2"
$PN"3"64;
"CS3"
$PN"27"39;
"PWM3"
$PN"4"40;
"PWM7"
$PN"8"63;
"CS1"
$PN"29"62;
"RGND1"
$PN"31"35;
"VSEN1"
$PN"32"35;
"VDDIO"
$PN"15"61;
"TEMP0"
$PN"36"60;
"VINSEN"
$PN"38"59;
"VMON||IINSEN"
$PN"37"23;
"VCCS"
$PN"40"58;
"PWM6"
$PN"7"57;
"PG0"
$PN"12"56;
"PWM1"
$PN"2"55;
"VSEN0"
$PN"21"54;
"PWM5"
$PN"6"26;
"PWM4"
$PN"5"53;
"PMSDA"
$PN"9"52;
"RGND0"
$PN"22"24;
"EN0"
$PN"13"51;
"NPMALERT \B"
$PN"11"50;
"SVD"
$PN"17"33;
"PG1"
$PN"16"49;
"CS4"
$PN"26"48;
"CS5"
$PN"25"47;
"RESET_L \B"
$PN"14"46;
"SVTO"
$PN"19"45;
"CS6"
$PN"24"44;
"SVC"
$PN"18"33;
"PMSCL"
$PN"10"43;
"SVTI"
$PN"20"33;
"VCC"
$PN"39"42;
"CS7"
$PN"23"41;
%"Q_RES"
"2","(-6000,2350)","0","pure_quanta","I25";
;
LOCATION"R124"
$SEC"1"
CDS_SEC"1"
TOLERANCE"1%"
VALUE"1K"
MATERIAL"EMPTY"
PACK_TYPE"0402LF"
WATTAGE"1/16W"
CDS_LIB"pure_quanta"
PART_NUMBER"CS21002FB06";
"A"
$PN"1"5;
"B"
$PN"2"66;
%"VCC_CORE"
"1","(-6000,2550)","0","pure_quanta_power","I26";
;
HDL_POWER"PVDD18_S5_P0"
CDS_LIB"pure_quanta_power";
"A"5;
%"UNIVERSAL_GND"
"1","(-5400,2575)","2","pure_quanta_power","I27";
;
CDS_LIB"pure_quanta_power"
HDL_POWER"GND";
"A"35;
%"Q_RES"
"1","(-6075,4075)","0","pure_quanta","I28";
;
LOCATION"PR121"
$SEC"1"
CDS_SEC"1"
TOLERANCE"5%"
WATTAGE"1/16W"
PACK_TYPE"0402LF"
VALUE"0"
MATERIAL"CHIP"
CDS_LIB"pure_quanta"
PART_NUMBER"CS00002JB13";
"B"
$PN"2"54;
"A"
$PN"1"25;
%"Q_CAP"
"1","(-5775,3950)","0","pure_quanta","I29";
;
LOCATION"PC194"
$SEC"1"
CDS_SEC"1"
MATERIAL"X7R"
TOLERANCE"10%"
VOLTAGE"50V"
PACK_TYPE"0402"
VALUE"3300PF"
CDS_LIB"pure_quanta"
PART_NUMBER"TMP_QCH2336K1B12";
"B"
$PN"2"24;
"A"
$PN"1"54;
%"UNIVERSAL_GND"
"1","(-6975,400)","0","pure_quanta_power","I3";
;
CDS_LIB"pure_quanta_power"
HDL_POWER"GND";
"A"6;
%"Q_RES"
"2","(-6900,4250)","0","pure_quanta","I30";
;
LOCATION"PR114"
$SEC"1"
CDS_SEC"1"
WATTAGE"1/16W"
VALUE"49.9"
MATERIAL"CHIP"
PACK_TYPE"0402LF"
TOLERANCE"1%"
CDS_LIB"pure_quanta"
PART_NUMBER"CS04992FB07";
"A"
$PN"1"7;
"B"
$PN"2"25;
%"VCC_CORE"
"1","(-6900,4450)","0","pure_quanta_power","I31";
;
HDL_POWER"PVDD11_S3_P0"
CDS_LIB"pure_quanta_power";
"A"7;
%"VCC_CORE"
"1","(-6625,6525)","0","pure_quanta_power","I37";
;
HDL_POWER"P3V3_AUX"
CDS_LIB"pure_quanta_power";
"A"34;
%"Q_RES"
"1","(-6225,6400)","0","pure_quanta","I38";
;
LOCATION"R117"
$SEC"1"
CDS_SEC"1"
MATERIAL"CHIP"
VALUE"1K"
TOLERANCE"1%"
WATTAGE"1/16W"
PACK_TYPE"0402LF"
CDS_LIB"pure_quanta"
PART_NUMBER"CS21002FB06";
"B"
$PN"2"56;
"A"
$PN"1"34;
%"Q_RES"
"1","(-6075,4675)","0","pure_quanta","I39";
;
LOCATION"R120"
$SEC"1"
CDS_SEC"1"
WATTAGE"1/16W"
VALUE"33"
MATERIAL"CHIP"
PACK_TYPE"0402LF"
TOLERANCE"5%"
CDS_LIB"pure_quanta"
PART_NUMBER"CS03302JB10";
"B"
$PN"2"50;
"A"
$PN"1"71;
%"Q_CAP"
"1","(-6975,675)","0","pure_quanta","I4";
;
LOCATION"PC193"
$SEC"1"
CDS_SEC"1"
VOLTAGE"25V"
TOLERANCE"10%"
MATERIAL"X7R"
PACK_TYPE"0402"
VALUE"0.1UF"
CDS_LIB"pure_quanta"
PART_NUMBER"CH4104K1B00";
"B"
$PN"2"6;
"A"
$PN"1"23;
%"Q_RES"
"1","(-6075,4825)","0","pure_quanta","I40";
;
LOCATION"R119"
$SEC"1"
CDS_SEC"1"
TOLERANCE"5%"
VALUE"0"
MATERIAL"CHIP"
PACK_TYPE"0402LF"
WATTAGE"1/16W"
CDS_LIB"pure_quanta"
PART_NUMBER"CS00002JB13";
"B"
$PN"2"52;
"A"
$PN"1"72;
%"Q_RES"
"1","(-6075,4975)","0","pure_quanta","I41";
;
LOCATION"R118"
$SEC"1"
CDS_SEC"1"
MATERIAL"CHIP"
PACK_TYPE"0402LF"
WATTAGE"1/16W"
TOLERANCE"5%"
VALUE"0"
CDS_LIB"pure_quanta"
PART_NUMBER"CS00002JB13";
"B"
$PN"2"43;
"A"
$PN"1"74;
%"UNIVERSAL_GND"
"1","(-6075,5125)","0","pure_quanta_power","I42";
;
CDS_LIB"pure_quanta_power"
HDL_POWER"GND";
"A"33;
%"Q_RES"
"1","(-6000,5975)","0","pure_quanta","I43";
;
LOCATION"R123"
$SEC"1"
CDS_SEC"1"
PACK_TYPE"0402LF"
VALUE"0"
MATERIAL"CHIP"
TOLERANCE"5%"
WATTAGE"1/16W"
CDS_LIB"pure_quanta"
PART_NUMBER"CS00002JB13";
"B"
$PN"2"51;
"A"
$PN"1"75;
%"Q_RES"
"1","(-6000,6125)","0","pure_quanta","I44";
;
LOCATION"R122"
$SEC"1"
CDS_SEC"1"
MATERIAL"CHIP"
WATTAGE"1/16W"
VALUE"0"
TOLERANCE"5%"
PACK_TYPE"0402LF"
CDS_LIB"pure_quanta"
PART_NUMBER"CS00002JB13";
"B"
$PN"2"56;
"A"
$PN"1"70;
%"Q_CAP"
"2","(-5325,5850)","0","pure_quanta","I45";
;
LOCATION"C197"
$SEC"1"
CDS_SEC"1"
VALUE"1000PF"
MATERIAL"X7R"
TOLERANCE"5%"
PACK_TYPE"0402"
VOLTAGE"50V"
CDS_LIB"pure_quanta"
PART_NUMBER"TMP_QCH21006JB10";
"A"
$PN"1"51;
"B"
$PN"2"32;
%"UNIVERSAL_GND"
"1","(-5100,5775)","0","pure_quanta_power","I46";
;
CDS_LIB"pure_quanta_power"
HDL_POWER"GND";
"A"32;
%"Q_CAP"
"2","(-5350,6400)","0","pure_quanta","I47";
;
LOCATION"C196"
$SEC"1"
CDS_SEC"1"
VOLTAGE"50V"
MATERIAL"EMPTY"
VALUE"1000PF"
PACK_TYPE"0402"
TOLERANCE"5%"
CDS_LIB"pure_quanta"
PART_NUMBER"TMP_QCH21006JB10";
"A"
$PN"1"56;
"B"
$PN"2"31;
%"UNIVERSAL_GND"
"1","(-5100,6325)","0","pure_quanta_power","I48";
;
CDS_LIB"pure_quanta_power"
HDL_POWER"GND";
"A"31;
%"UNIVERSAL_GND"
"1","(-3475,450)","0","pure_quanta_power","I49";
;
CDS_LIB"pure_quanta_power"
HDL_POWER"GND";
"A"8;
%"UNIVERSAL_GND"
"1","(-6550,400)","0","pure_quanta_power","I5";
;
CDS_LIB"pure_quanta_power"
HDL_POWER"GND";
"A"9;
%"Q_CAP"
"1","(-3475,725)","0","pure_quanta","I50";
;
LOCATION"PC198"
$SEC"1"
CDS_SEC"1"
PACK_TYPE"0402"
VOLTAGE"50V"
VALUE"470PF"
TOLERANCE"10%"
MATERIAL"X7R"
CDS_LIB"pure_quanta"
PART_NUMBER"TMP_QCH14706KB18";
"B"
$PN"2"8;
"A"
$PN"1"60;
%"Q_RES"
"1","(-3150,1225)","0","pure_quanta","I52";
;
LOCATION"PR412"
$SEC"1"
CDS_SEC"1"
WATTAGE"1/16W"
MATERIAL"CHIP"
TOLERANCE"5%"
VALUE"0"
PACK_TYPE"0402LF"
CDS_LIB"pure_quanta"
PART_NUMBER"CS00002JB13";
"B"
$PN"2"10;
"A"
$PN"1"67;
%"Q_RES"
"1","(-3150,1875)","0","pure_quanta","I53";
;
LOCATION"PR36"
$SEC"1"
CDS_SEC"1"
MATERIAL"CHIP"
TOLERANCE"5%"
PACK_TYPE"0402LF"
VALUE"0"
WATTAGE"1/16W"
CDS_LIB"pure_quanta"
PART_NUMBER"CS00002JB13";
"B"
$PN"2"11;
"A"
$PN"1"69;
%"UNIVERSAL_GND"
"1","(-2700,1150)","0","pure_quanta_power","I54";
;
CDS_LIB"pure_quanta_power"
HDL_POWER"GND";
"A"10;
%"UNIVERSAL_GND"
"1","(-2700,1800)","0","pure_quanta_power","I55";
;
CDS_LIB"pure_quanta_power"
HDL_POWER"GND";
"A"11;
%"UNIVERSAL_GND"
"1","(-2175,1200)","0","pure_quanta_power","I56";
;
CDS_LIB"pure_quanta_power"
HDL_POWER"GND";
"A"12;
%"Q_RES"
"2","(-2175,1425)","0","pure_quanta","I57";
;
LOCATION"PR127"
$SEC"1"
CDS_SEC"1"
WATTAGE"1/16W"
MATERIAL"EMPTY"
TOLERANCE"5%"
VALUE"0"
PACK_TYPE"0402LF"
CDS_LIB"pure_quanta"
PART_NUMBER"CS00002JB13";
"A"
$PN"1"46;
"B"
$PN"2"12;
%"Q_RES"
"1","(-3150,2325)","0","pure_quanta","I58";
;
LOCATION"PR419"
$SEC"1"
CDS_SEC"1"
WATTAGE"1/16W"
MATERIAL"CHIP"
TOLERANCE"5%"
VALUE"0"
PACK_TYPE"0402LF"
CDS_LIB"pure_quanta"
PART_NUMBER"CS00002JB13";
"B"
$PN"2"13;
"A"
$PN"1"62;
%"Q_RES"
"1","(-3150,2775)","0","pure_quanta","I59";
;
LOCATION"PR35"
$SEC"1"
CDS_SEC"1"
PACK_TYPE"0402LF"
WATTAGE"1/16W"
MATERIAL"CHIP"
TOLERANCE"5%"
VALUE"0"
CDS_LIB"pure_quanta"
PART_NUMBER"CS00002JB13";
"B"
$PN"2"14;
"A"
$PN"1"65;
%"Q_RES"
"2","(-6550,675)","0","pure_quanta","I6";
;
LOCATION"PR3"
SEC"1"
MATERIAL"CHIP"
VALUE"10K"
PACK_TYPE"0402LF"
TOLERANCE"1%"
WATTAGE"1/16W"
CDS_LIB"pure_quanta"
SEC_TYPE"0402LF"
PART_NUMBER"CS31002FB08";
"A"
$PN"1"23;
"B"
$PN"2"9;
%"Q_RES"
"1","(-3150,3225)","0","pure_quanta","I60";
;
LOCATION"PR34"
$SEC"1"
CDS_SEC"1"
WATTAGE"1/16W"
MATERIAL"CHIP"
TOLERANCE"5%"
VALUE"0"
PACK_TYPE"0402LF"
CDS_LIB"pure_quanta"
PART_NUMBER"CS00002JB13";
"B"
$PN"2"15;
"A"
$PN"1"39;
%"Q_RES"
"1","(-3150,3675)","0","pure_quanta","I61";
;
LOCATION"PR33"
$SEC"1"
CDS_SEC"1"
WATTAGE"1/16W"
MATERIAL"CHIP"
TOLERANCE"5%"
VALUE"0"
PACK_TYPE"0402LF"
CDS_LIB"pure_quanta"
PART_NUMBER"CS00002JB13";
"B"
$PN"2"16;
"A"
$PN"1"48;
%"UNIVERSAL_GND"
"1","(-2700,2250)","0","pure_quanta_power","I62";
;
CDS_LIB"pure_quanta_power"
HDL_POWER"GND";
"A"13;
%"UNIVERSAL_GND"
"1","(-2700,2700)","0","pure_quanta_power","I63";
;
CDS_LIB"pure_quanta_power"
HDL_POWER"GND";
"A"14;
%"UNIVERSAL_GND"
"1","(-2700,3150)","0","pure_quanta_power","I64";
;
CDS_LIB"pure_quanta_power"
HDL_POWER"GND";
"A"15;
%"UNIVERSAL_GND"
"1","(-2700,3600)","0","pure_quanta_power","I65";
;
CDS_LIB"pure_quanta_power"
HDL_POWER"GND";
"A"16;
%"UNIVERSAL_GND"
"1","(-2700,4050)","0","pure_quanta_power","I66";
;
CDS_LIB"pure_quanta_power"
HDL_POWER"GND";
"A"17;
%"Q_RES"
"1","(-1700,1625)","0","pure_quanta","I67";
;
LOCATION"PR129"
$SEC"1"
CDS_SEC"1"
WATTAGE"1/16W"
TOLERANCE"5%"
PACK_TYPE"0402LF"
VALUE"0"
MATERIAL"EMPTY"
CDS_LIB"pure_quanta"
PART_NUMBER"CS00002JB13";
"B"
$PN"2"76;
"A"
$PN"1"46;
%"Q_RES"
"1","(-1750,1850)","0","pure_quanta","I68";
;
LOCATION"PR128"
$SEC"1"
CDS_SEC"1"
WATTAGE"1/16W"
MATERIAL"EMPTY"
TOLERANCE"1%"
PACK_TYPE"0402LF"
VALUE"1K"
CDS_LIB"pure_quanta"
PART_NUMBER"CS21002FB06";
"B"
$PN"2"30;
"A"
$PN"1"46;
%"VCC_CORE"
"1","(-1400,2000)","0","pure_quanta_power","I69";
;
HDL_POWER"PVDD18_S5_P0"
CDS_LIB"pure_quanta_power";
"A"30;
%"VCC_CORE"
"1","(-6275,750)","0","pure_quanta_power","I7";
;
HDL_POWER"P12V_AUX"
CDS_LIB"pure_quanta_power";
"A"29;
%"Q_RES"
"1","(-3125,4125)","0","pure_quanta","I71";
;
LOCATION"PR37"
$SEC"1"
CDS_SEC"1"
WATTAGE"1/16W"
MATERIAL"CHIP"
TOLERANCE"5%"
VALUE"0"
PACK_TYPE"0402LF"
CDS_LIB"pure_quanta"
PART_NUMBER"CS00002JB13";
"B"
$PN"2"17;
"A"
$PN"1"47;
%"UNIVERSAL_GND"
"1","(-3425,5450)","0","pure_quanta_power","I76";
;
CDS_LIB"pure_quanta_power"
HDL_POWER"GND";
"A"18;
%"Q_CAP"
"1","(-3425,5650)","0","pure_quanta","I77";
;
LOCATION"PC9"
$SEC"1"
CDS_SEC"1"
PACK_TYPE"0402"
VOLTAGE"25V"
VALUE"0.1UF"
TOLERANCE"10%"
MATERIAL"X7R"
CDS_LIB"pure_quanta"
PART_NUMBER"CH4104K1B00";
"B"
$PN"2"18;
"A"
$PN"1"58;
%"UNIVERSAL_GND"
"1","(-3425,5900)","0","pure_quanta_power","I78";
;
CDS_LIB"pure_quanta_power"
HDL_POWER"GND";
"A"19;
%"Q_CAP"
"1","(-3425,6150)","0","pure_quanta","I79";
;
LOCATION"PC4"
$SEC"1"
CDS_SEC"1"
VOLTAGE"25V"
VALUE"0.1UF"
TOLERANCE"10%"
MATERIAL"X7R"
PACK_TYPE"0402"
CDS_LIB"pure_quanta"
PART_NUMBER"CH4104K1B00";
"B"
$PN"2"19;
"A"
$PN"1"42;
%"VCC_CORE"
"1","(-6625,1850)","0","pure_quanta_power","I8";
;
HDL_POWER"P3V3_AUX"
CDS_LIB"pure_quanta_power";
"A"28;
%"Q_CAP"
"1","(-3025,5675)","0","pure_quanta","I80";
;
LOCATION"PC199"
$SEC"1"
CDS_SEC"1"
TOLERANCE"20%"
MATERIAL"X6S"
VALUE"10UF"
VOLTAGE"6.3V"
PACK_TYPE"C0402"
CDS_LIB"pure_quanta"
PART_NUMBER"CH6101MEB03";
"B"
$PN"2"20;
"A"
$PN"1"58;
%"UNIVERSAL_GND"
"1","(-3025,5450)","0","pure_quanta_power","I81";
;
CDS_LIB"pure_quanta_power"
HDL_POWER"GND";
"A"20;
%"Q_CAP"
"1","(-3025,6150)","0","pure_quanta","I82";
;
LOCATION"PC200"
$SEC"1"
CDS_SEC"1"
VOLTAGE"16V"
VALUE"1UF"
TOLERANCE"10%"
MATERIAL"X6S"
PACK_TYPE"C0402"
CDS_LIB"pure_quanta"
PART_NUMBER"CH5103KEB01";
"B"
$PN"2"21;
"A"
$PN"1"42;
%"UNIVERSAL_GND"
"1","(-3025,5950)","0","pure_quanta_power","I83";
;
CDS_LIB"pure_quanta_power"
HDL_POWER"GND";
"A"21;
%"Q_RES"
"1","(-2600,6300)","0","pure_quanta","I85";
;
LOCATION"PR130"
$SEC"1"
CDS_SEC"1"
VALUE"1"
TOLERANCE"1%"
PACK_TYPE"0402LF"
MATERIAL"CHIP"
WATTAGE"1/16W"
CDS_LIB"pure_quanta"
PART_NUMBER"CS-1002FB04";
"B"
$PN"2"27;
"A"
$PN"1"42;
%"VCC_CORE"
"1","(-2225,6400)","0","pure_quanta_power","I86";
;
HDL_POWER"P3V3_AUX"
CDS_LIB"pure_quanta_power";
"A"27;
%"UNIVERSAL_GND"
"1","(-6500,4300)","0","pure_quanta_power","I87";
;
CDS_LIB"pure_quanta_power"
HDL_POWER"GND";
"A"22;
%"Q_CAP"
"1","(-6500,4500)","0","pure_quanta","I88";
;
LOCATION"C5009"
$SEC"1"
CDS_SEC"1"
VOLTAGE"50V"
TOLERANCE"5%"
PACK_TYPE"0402"
VALUE"1000PF"
MATERIAL"X7R"
CDS_LIB"pure_quanta"
PART_NUMBER"TMP_QCH21006JB10";
"B"
$PN"2"22;
"A"
$PN"1"71;
%"Q_RES"
"1","(-6200,1725)","0","pure_quanta","I9";
;
LOCATION"R8458"
$SEC"1"
CDS_SEC"1"
MATERIAL"EMPTY"
VALUE"0"
TOLERANCE"5%"
PACK_TYPE"0402LF"
WATTAGE"1/16W"
CDS_LIB"pure_quanta"
PART_NUMBER"CS00002JB13";
"B"
$PN"2"61;
"A"
$PN"1"28;
END.
